(kicad_pcb
	(version 20260206)
	(generator "pcbnew")
	(generator_version "10.0")
	(general
		(thickness 1.6)
		(legacy_teardrops no)
	)
	(paper "A4")
	(title_block
		(title "panther-plus-userver — 13130-1b_20150205.brd")
		(comment 1 "Honey Badger (Wiwynn) / footprint 406 of 1509 (DIMM2), pads 23-29 of 210")
	)
	(layers
		(0 "F.Cu" signal "TOP")
		(4 "In1.Cu" signal "L2")
		(6 "In2.Cu" signal "L3")
		(8 "In3.Cu" signal "L4")
		(10 "In4.Cu" signal "L5")
		(12 "In5.Cu" signal "L6")
		(14 "In6.Cu" signal "L7")
		(16 "In7.Cu" signal "L8")
		(18 "In8.Cu" signal "L9")
		(20 "In9.Cu" signal "L10")
		(22 "In10.Cu" signal "L11")
		(2 "B.Cu" signal "BOTTOM")
		(9 "F.Adhes" user "F.Adhesive")
		(11 "B.Adhes" user "B.Adhesive")
		(13 "F.Paste" user "Package Geometry/Pastemask Top")
		(15 "B.Paste" user "Package Geometry/Pastemask Bottom")
		(5 "F.SilkS" user "Ref Des/Silkscreen Top")
		(7 "B.SilkS" user "Ref Des/Silkscreen Bottom")
		(1 "F.Mask" user "Board Geometry/Soldermask Top")
		(3 "B.Mask" user "Board Geometry/Soldermask Bottom")
		(17 "Dwgs.User" user "User.Drawings")
		(19 "Cmts.User" user "User.Comments")
		(21 "Eco1.User" user "User.Eco1")
		(23 "Eco2.User" user "User.Eco2")
		(25 "Edge.Cuts" user "Board Geometry/Outline")
		(27 "Margin" user)
		(31 "F.CrtYd" user "Package Geometry/Place Bound Top")
		(29 "B.CrtYd" user "Package Geometry/Place Bound Bottom")
		(35 "F.Fab" user "Ref Des/Assembly Top")
		(33 "B.Fab" user "Ref Des/Assembly Bottom")
	)
	(footprint ""
		(layer "F.Cu")
		(at 158.500064 -66.699892 180)
		(property "Reference" "DIMM2"
			(at 0 0 180)
			(layer "F.SilkS")
			(hide yes)
			(effects
				(font
					(size 1.27 1.27)
				)
			)
		)
		(property "Value" "DDR3-204P-174-COLAY-1-GP"
			(at -40.682164 -17.468088 180)
			(unlocked yes)
			(layer "F.Fab")
			(hide yes)
			(effects
				(font
					(size 1.016 1.016)
					(thickness 0.1524)
				)
			)
		)
		(property "Device Type" "AS0A626-H8SN-7H-COLAY-1"
			(at -40.682164 -18.992088 180)
			(unlocked yes)
			(layer "F.Fab")
			(hide yes)
			(effects
				(font
					(size 1.016 1.016)
					(thickness 0.1524)
				)
			)
		)
		(duplicate_pad_numbers_are_jumpers no)
		(pad "21" smd custom
			(at -25.649936 4.106672 180)
			(size 0.1143 0.1143)
			(layers "F.Cu" "F.Mask" "F.Paste")
			(net "M_A_DQ13")
			(options
				(clearance outline)
				(anchor circle)
			)
			(primitives
				(gr_poly
					(pts
						(xy 0 0.9017) (xy -0.03175 0.89916) (xy -0.0635 0.889) (xy -0.09144 0.87376) (xy -0.11684 0.85344)
						(xy -0.13716 0.82804) (xy -0.1524 0.8001) (xy -0.16256 0.76835) (xy -0.1651 0.7366) (xy -0.1651 -0.13462)
						(xy -0.17272 -0.14224) (xy -0.19812 -0.1778) (xy -0.2032 -0.18796) (xy -0.20701 -0.19685) (xy -0.21209 -0.20701)
						(xy -0.2159 -0.21717) (xy -0.21844 -0.22733) (xy -0.22225 -0.23876) (xy -0.22352 -0.24892) (xy -0.22606 -0.25908)
						(xy -0.22733 -0.27051) (xy -0.22733 -0.28067) (xy -0.2286 -0.2921) (xy -0.22733 -0.30353) (xy -0.22733 -0.31369)
						(xy -0.22606 -0.32512) (xy -0.22352 -0.33528) (xy -0.22225 -0.34544) (xy -0.21844 -0.35687) (xy -0.2159 -0.36703)
						(xy -0.21209 -0.37719) (xy -0.20701 -0.38735) (xy -0.2032 -0.39624) (xy -0.19812 -0.4064) (xy -0.17272 -0.44196)
						(xy -0.1651 -0.44958) (xy -0.1651 -0.7366) (xy -0.16256 -0.76835) (xy -0.1524 -0.8001) (xy -0.13716 -0.82804)
						(xy -0.11684 -0.85344) (xy -0.09144 -0.87376) (xy -0.0635 -0.889) (xy -0.03175 -0.89916) (xy 0 -0.9017)
						(xy 0.03175 -0.89916) (xy 0.0635 -0.889) (xy 0.09144 -0.87376) (xy 0.11684 -0.85344) (xy 0.13716 -0.82804)
						(xy 0.1524 -0.8001) (xy 0.16256 -0.76835) (xy 0.1651 -0.7366) (xy 0.1651 -0.44958) (xy 0.17272 -0.44196)
						(xy 0.19812 -0.4064) (xy 0.2032 -0.39624) (xy 0.20701 -0.38735) (xy 0.21209 -0.37719) (xy 0.2159 -0.36703)
						(xy 0.21844 -0.35687) (xy 0.22225 -0.34544) (xy 0.22352 -0.33528) (xy 0.22606 -0.32512) (xy 0.22733 -0.31369)
						(xy 0.22733 -0.30353) (xy 0.2286 -0.2921) (xy 0.22733 -0.28067) (xy 0.22733 -0.27051) (xy 0.22606 -0.25908)
						(xy 0.22352 -0.24892) (xy 0.22225 -0.23876) (xy 0.21844 -0.22733) (xy 0.2159 -0.21717) (xy 0.21209 -0.20701)
						(xy 0.20701 -0.19685) (xy 0.2032 -0.18796) (xy 0.19812 -0.1778) (xy 0.17272 -0.14224) (xy 0.1651 -0.13462)
						(xy 0.1651 0.7366) (xy 0.16256 0.76835) (xy 0.1524 0.8001) (xy 0.13716 0.82804) (xy 0.11684 0.85344)
						(xy 0.09144 0.87376) (xy 0.0635 0.889) (xy 0.03175 0.89916)
					)
					(width 0)
					(fill yes)
				)
			)
		)
		(pad "22" smd custom
			(at -25.349962 -4.106672 180)
			(size 0.1143 0.1143)
			(layers "F.Cu" "F.Mask" "F.Paste")
			(net "M_A_DQ8")
			(options
				(clearance outline)
				(anchor circle)
			)
			(primitives
				(gr_poly
					(pts
						(xy 0 0.9017) (xy -0.03175 0.89916) (xy -0.0635 0.889) (xy -0.09144 0.87376) (xy -0.11684 0.85344)
						(xy -0.13716 0.82804) (xy -0.1524 0.8001) (xy -0.16256 0.76835) (xy -0.1651 0.7366) (xy -0.1651 0.44958)
						(xy -0.17272 0.44196) (xy -0.19812 0.4064) (xy -0.2032 0.39624) (xy -0.20701 0.38735) (xy -0.21209 0.37719)
						(xy -0.2159 0.36703) (xy -0.21844 0.35687) (xy -0.22225 0.34544) (xy -0.22352 0.33528) (xy -0.22606 0.32512)
						(xy -0.22733 0.31369) (xy -0.22733 0.30353) (xy -0.2286 0.2921) (xy -0.22733 0.28067) (xy -0.22733 0.27051)
						(xy -0.22606 0.25908) (xy -0.22352 0.24892) (xy -0.22225 0.23876) (xy -0.21844 0.22733) (xy -0.2159 0.21717)
						(xy -0.21209 0.20701) (xy -0.20701 0.19685) (xy -0.2032 0.18796) (xy -0.19812 0.1778) (xy -0.17272 0.14224)
						(xy -0.1651 0.13462) (xy -0.1651 -0.7366) (xy -0.16256 -0.76835) (xy -0.1524 -0.8001) (xy -0.13716 -0.82804)
						(xy -0.11684 -0.85344) (xy -0.09144 -0.87376) (xy -0.0635 -0.889) (xy -0.03175 -0.89916) (xy 0 -0.9017)
						(xy 0.03175 -0.89916) (xy 0.0635 -0.889) (xy 0.09144 -0.87376) (xy 0.11684 -0.85344) (xy 0.13716 -0.82804)
						(xy 0.1524 -0.8001) (xy 0.16256 -0.76835) (xy 0.1651 -0.7366) (xy 0.1651 0.13462) (xy 0.17272 0.14224)
						(xy 0.19812 0.1778) (xy 0.2032 0.18796) (xy 0.20701 0.19685) (xy 0.21209 0.20701) (xy 0.2159 0.21717)
						(xy 0.21844 0.22733) (xy 0.22225 0.23876) (xy 0.22352 0.24892) (xy 0.22606 0.25908) (xy 0.22733 0.27051)
						(xy 0.22733 0.28067) (xy 0.2286 0.2921) (xy 0.22733 0.30353) (xy 0.22733 0.31369) (xy 0.22606 0.32512)
						(xy 0.22352 0.33528) (xy 0.22225 0.34544) (xy 0.21844 0.35687) (xy 0.2159 0.36703) (xy 0.21209 0.37719)
						(xy 0.20701 0.38735) (xy 0.2032 0.39624) (xy 0.19812 0.4064) (xy 0.17272 0.44196) (xy 0.1651 0.44958)
						(xy 0.1651 0.7366) (xy 0.16256 0.76835) (xy 0.1524 0.8001) (xy 0.13716 0.82804) (xy 0.11684 0.85344)
						(xy 0.09144 0.87376) (xy 0.0635 0.889) (xy 0.03175 0.89916)
					)
					(width 0)
					(fill yes)
				)
			)
		)
		(pad "23" smd custom
			(at -25.049988 4.106672 180)
			(size 0.1143 0.1143)
			(layers "F.Cu" "F.Mask" "F.Paste")
			(net "GND")
			(options
				(clearance outline)
				(anchor circle)
			)
			(primitives
				(gr_poly
					(pts
						(xy 0 0.9017) (xy -0.03175 0.89916) (xy -0.0635 0.889) (xy -0.09144 0.87376) (xy -0.11684 0.85344)
						(xy -0.13716 0.82804) (xy -0.1524 0.8001) (xy -0.16256 0.76835) (xy -0.1651 0.7366) (xy -0.1651 0.11938)
						(xy -0.17272 0.11176) (xy -0.19812 0.0762) (xy -0.2032 0.06604) (xy -0.20701 0.05715) (xy -0.21209 0.04699)
						(xy -0.2159 0.03683) (xy -0.21844 0.02667) (xy -0.22225 0.01524) (xy -0.22352 0.00508) (xy -0.22606 -0.00508)
						(xy -0.22733 -0.01651) (xy -0.22733 -0.02667) (xy -0.2286 -0.0381) (xy -0.22733 -0.04953) (xy -0.22733 -0.05969)
						(xy -0.22606 -0.07112) (xy -0.22352 -0.08128) (xy -0.22225 -0.09144) (xy -0.21844 -0.10287) (xy -0.2159 -0.11303)
						(xy -0.21209 -0.12319) (xy -0.20701 -0.13335) (xy -0.2032 -0.14224) (xy -0.19812 -0.1524) (xy -0.17272 -0.18796)
						(xy -0.1651 -0.19558) (xy -0.1651 -0.7366) (xy -0.16256 -0.76835) (xy -0.1524 -0.8001) (xy -0.13716 -0.82804)
						(xy -0.11684 -0.85344) (xy -0.09144 -0.87376) (xy -0.0635 -0.889) (xy -0.03175 -0.89916) (xy 0 -0.9017)
						(xy 0.03175 -0.89916) (xy 0.0635 -0.889) (xy 0.09144 -0.87376) (xy 0.11684 -0.85344) (xy 0.13716 -0.82804)
						(xy 0.1524 -0.8001) (xy 0.16256 -0.76835) (xy 0.1651 -0.7366) (xy 0.1651 -0.19685) (xy 0.17272 -0.18923)
						(xy 0.17907 -0.18034) (xy 0.18669 -0.17145) (xy 0.19177 -0.16256) (xy 0.19812 -0.15367) (xy 0.20828 -0.13335)
						(xy 0.21971 -0.10287) (xy 0.22225 -0.09271) (xy 0.22479 -0.08128) (xy 0.22606 -0.07112) (xy 0.2286 -0.05969)
						(xy 0.2286 -0.01651) (xy 0.22606 -0.00508) (xy 0.22479 0.00508) (xy 0.22225 0.01651) (xy 0.21971 0.02667)
						(xy 0.20828 0.05715) (xy 0.19812 0.07747) (xy 0.19177 0.08636) (xy 0.18669 0.09525) (xy 0.17907 0.10414)
						(xy 0.17272 0.11303) (xy 0.1651 0.12065) (xy 0.1651 0.7366) (xy 0.16256 0.76835) (xy 0.1524 0.8001)
						(xy 0.13716 0.82804) (xy 0.11684 0.85344) (xy 0.09144 0.87376) (xy 0.0635 0.889) (xy 0.03175 0.89916)
					)
					(width 0)
					(fill yes)
				)
			)
		)
		(pad "24" smd custom
			(at -24.750014 -4.106672 180)
			(size 0.1143 0.1143)
			(layers "F.Cu" "F.Mask" "F.Paste")
			(net "M_A_DQ9")
			(options
				(clearance outline)
				(anchor circle)
			)
			(primitives
				(gr_poly
					(pts
						(xy 0 0.9017) (xy -0.03175 0.89916) (xy -0.0635 0.889) (xy -0.09144 0.87376) (xy -0.11684 0.85344)
						(xy -0.13716 0.82804) (xy -0.1524 0.8001) (xy -0.16256 0.76835) (xy -0.1651 0.7366) (xy -0.1651 0.19685)
						(xy -0.17272 0.18923) (xy -0.17907 0.18034) (xy -0.18669 0.17145) (xy -0.19177 0.16256) (xy -0.19812 0.15367)
						(xy -0.20828 0.13335) (xy -0.21971 0.10287) (xy -0.22225 0.09271) (xy -0.22479 0.08128) (xy -0.22606 0.07112)
						(xy -0.2286 0.05969) (xy -0.2286 0.01651) (xy -0.22606 0.00508) (xy -0.22479 -0.00508) (xy -0.22225 -0.01651)
						(xy -0.21971 -0.02667) (xy -0.20828 -0.05715) (xy -0.19812 -0.07747) (xy -0.19177 -0.08636) (xy -0.18669 -0.09525)
						(xy -0.17907 -0.10414) (xy -0.17272 -0.11303) (xy -0.1651 -0.12065) (xy -0.1651 -0.7366) (xy -0.16256 -0.76835)
						(xy -0.1524 -0.8001) (xy -0.13716 -0.82804) (xy -0.11684 -0.85344) (xy -0.09144 -0.87376) (xy -0.0635 -0.889)
						(xy -0.03175 -0.89916) (xy 0 -0.9017) (xy 0.03175 -0.89916) (xy 0.0635 -0.889) (xy 0.09144 -0.87376)
						(xy 0.11684 -0.85344) (xy 0.13716 -0.82804) (xy 0.1524 -0.8001) (xy 0.16256 -0.76835) (xy 0.1651 -0.7366)
						(xy 0.1651 -0.11938) (xy 0.17272 -0.11176) (xy 0.19812 -0.0762) (xy 0.2032 -0.06604) (xy 0.20701 -0.05715)
						(xy 0.21209 -0.04699) (xy 0.2159 -0.03683) (xy 0.21844 -0.02667) (xy 0.22225 -0.01524) (xy 0.22352 -0.00508)
						(xy 0.22606 0.00508) (xy 0.22733 0.01651) (xy 0.22733 0.02667) (xy 0.2286 0.0381) (xy 0.22733 0.04953)
						(xy 0.22733 0.05969) (xy 0.22606 0.07112) (xy 0.22352 0.08128) (xy 0.22225 0.09144) (xy 0.21844 0.10287)
						(xy 0.2159 0.11303) (xy 0.21209 0.12319) (xy 0.20701 0.13335) (xy 0.2032 0.14224) (xy 0.19812 0.1524)
						(xy 0.17272 0.18796) (xy 0.1651 0.19558) (xy 0.1651 0.7366) (xy 0.16256 0.76835) (xy 0.1524 0.8001)
						(xy 0.13716 0.82804) (xy 0.11684 0.85344) (xy 0.09144 0.87376) (xy 0.0635 0.889) (xy 0.03175 0.89916)
					)
					(width 0)
					(fill yes)
				)
			)
		)
		(pad "25" smd custom
			(at -24.45004 4.106672 180)
			(size 0.1143 0.1143)
			(layers "F.Cu" "F.Mask" "F.Paste")
			(net "M_A_DQS_DN1")
			(options
				(clearance outline)
				(anchor circle)
			)
			(primitives
				(gr_poly
					(pts
						(xy 0 0.9017) (xy -0.03175 0.89916) (xy -0.0635 0.889) (xy -0.09144 0.87376) (xy -0.11684 0.85344)
						(xy -0.13716 0.82804) (xy -0.1524 0.8001) (xy -0.16256 0.76835) (xy -0.1651 0.7366) (xy -0.1651 -0.13462)
						(xy -0.17272 -0.14224) (xy -0.19812 -0.1778) (xy -0.2032 -0.18796) (xy -0.20701 -0.19685) (xy -0.21209 -0.20701)
						(xy -0.2159 -0.21717) (xy -0.21844 -0.22733) (xy -0.22225 -0.23876) (xy -0.22352 -0.24892) (xy -0.22606 -0.25908)
						(xy -0.22733 -0.27051) (xy -0.22733 -0.28067) (xy -0.2286 -0.2921) (xy -0.22733 -0.30353) (xy -0.22733 -0.31369)
						(xy -0.22606 -0.32512) (xy -0.22352 -0.33528) (xy -0.22225 -0.34544) (xy -0.21844 -0.35687) (xy -0.2159 -0.36703)
						(xy -0.21209 -0.37719) (xy -0.20701 -0.38735) (xy -0.2032 -0.39624) (xy -0.19812 -0.4064) (xy -0.17272 -0.44196)
						(xy -0.1651 -0.44958) (xy -0.1651 -0.7366) (xy -0.16256 -0.76835) (xy -0.1524 -0.8001) (xy -0.13716 -0.82804)
						(xy -0.11684 -0.85344) (xy -0.09144 -0.87376) (xy -0.0635 -0.889) (xy -0.03175 -0.89916) (xy 0 -0.9017)
						(xy 0.03175 -0.89916) (xy 0.0635 -0.889) (xy 0.09144 -0.87376) (xy 0.11684 -0.85344) (xy 0.13716 -0.82804)
						(xy 0.1524 -0.8001) (xy 0.16256 -0.76835) (xy 0.1651 -0.7366) (xy 0.1651 -0.44958) (xy 0.17272 -0.44196)
						(xy 0.19812 -0.4064) (xy 0.2032 -0.39624) (xy 0.20701 -0.38735) (xy 0.21209 -0.37719) (xy 0.2159 -0.36703)
						(xy 0.21844 -0.35687) (xy 0.22225 -0.34544) (xy 0.22352 -0.33528) (xy 0.22606 -0.32512) (xy 0.22733 -0.31369)
						(xy 0.22733 -0.30353) (xy 0.2286 -0.2921) (xy 0.22733 -0.28067) (xy 0.22733 -0.27051) (xy 0.22606 -0.25908)
						(xy 0.22352 -0.24892) (xy 0.22225 -0.23876) (xy 0.21844 -0.22733) (xy 0.2159 -0.21717) (xy 0.21209 -0.20701)
						(xy 0.20701 -0.19685) (xy 0.2032 -0.18796) (xy 0.19812 -0.1778) (xy 0.17272 -0.14224) (xy 0.1651 -0.13462)
						(xy 0.1651 0.7366) (xy 0.16256 0.76835) (xy 0.1524 0.8001) (xy 0.13716 0.82804) (xy 0.11684 0.85344)
						(xy 0.09144 0.87376) (xy 0.0635 0.889) (xy 0.03175 0.89916)
					)
					(width 0)
					(fill yes)
				)
			)
		)
		(pad "26" smd custom
			(at -24.150066 -4.106672 180)
			(size 0.1143 0.1143)
			(layers "F.Cu" "F.Mask" "F.Paste")
			(net "GND")
			(options
				(clearance outline)
				(anchor circle)
			)
			(primitives
				(gr_poly
					(pts
						(xy 0 0.9017) (xy -0.03175 0.89916) (xy -0.0635 0.889) (xy -0.09144 0.87376) (xy -0.11684 0.85344)
						(xy -0.13716 0.82804) (xy -0.1524 0.8001) (xy -0.16256 0.76835) (xy -0.1651 0.7366) (xy -0.1651 0.44958)
						(xy -0.17272 0.44196) (xy -0.19812 0.4064) (xy -0.2032 0.39624) (xy -0.20701 0.38735) (xy -0.21209 0.37719)
						(xy -0.2159 0.36703) (xy -0.21844 0.35687) (xy -0.22225 0.34544) (xy -0.22352 0.33528) (xy -0.22606 0.32512)
						(xy -0.22733 0.31369) (xy -0.22733 0.30353) (xy -0.2286 0.2921) (xy -0.22733 0.28067) (xy -0.22733 0.27051)
						(xy -0.22606 0.25908) (xy -0.22352 0.24892) (xy -0.22225 0.23876) (xy -0.21844 0.22733) (xy -0.2159 0.21717)
						(xy -0.21209 0.20701) (xy -0.20701 0.19685) (xy -0.2032 0.18796) (xy -0.19812 0.1778) (xy -0.17272 0.14224)
						(xy -0.1651 0.13462) (xy -0.1651 -0.7366) (xy -0.16256 -0.76835) (xy -0.1524 -0.8001) (xy -0.13716 -0.82804)
						(xy -0.11684 -0.85344) (xy -0.09144 -0.87376) (xy -0.0635 -0.889) (xy -0.03175 -0.89916) (xy 0 -0.9017)
						(xy 0.03175 -0.89916) (xy 0.0635 -0.889) (xy 0.09144 -0.87376) (xy 0.11684 -0.85344) (xy 0.13716 -0.82804)
						(xy 0.1524 -0.8001) (xy 0.16256 -0.76835) (xy 0.1651 -0.7366) (xy 0.1651 0.13462) (xy 0.17272 0.14224)
						(xy 0.19812 0.1778) (xy 0.2032 0.18796) (xy 0.20701 0.19685) (xy 0.21209 0.20701) (xy 0.2159 0.21717)
						(xy 0.21844 0.22733) (xy 0.22225 0.23876) (xy 0.22352 0.24892) (xy 0.22606 0.25908) (xy 0.22733 0.27051)
						(xy 0.22733 0.28067) (xy 0.2286 0.2921) (xy 0.22733 0.30353) (xy 0.22733 0.31369) (xy 0.22606 0.32512)
						(xy 0.22352 0.33528) (xy 0.22225 0.34544) (xy 0.21844 0.35687) (xy 0.2159 0.36703) (xy 0.21209 0.37719)
						(xy 0.20701 0.38735) (xy 0.2032 0.39624) (xy 0.19812 0.4064) (xy 0.17272 0.44196) (xy 0.1651 0.44958)
						(xy 0.1651 0.7366) (xy 0.16256 0.76835) (xy 0.1524 0.8001) (xy 0.13716 0.82804) (xy 0.11684 0.85344)
						(xy 0.09144 0.87376) (xy 0.0635 0.889) (xy 0.03175 0.89916)
					)
					(width 0)
					(fill yes)
				)
			)
		)
		(pad "27" smd custom
			(at -23.850092 4.106672 180)
			(size 0.1143 0.1143)
			(layers "F.Cu" "F.Mask" "F.Paste")
			(net "M_A_DQS_DP1")
			(options
				(clearance outline)
				(anchor circle)
			)
			(primitives
				(gr_poly
					(pts
						(xy 0 0.9017) (xy -0.03175 0.89916) (xy -0.0635 0.889) (xy -0.09144 0.87376) (xy -0.11684 0.85344)
						(xy -0.13716 0.82804) (xy -0.1524 0.8001) (xy -0.16256 0.76835) (xy -0.1651 0.7366) (xy -0.1651 0.11938)
						(xy -0.17272 0.11176) (xy -0.19812 0.0762) (xy -0.2032 0.06604) (xy -0.20701 0.05715) (xy -0.21209 0.04699)
						(xy -0.2159 0.03683) (xy -0.21844 0.02667) (xy -0.22225 0.01524) (xy -0.22352 0.00508) (xy -0.22606 -0.00508)
						(xy -0.22733 -0.01651) (xy -0.22733 -0.02667) (xy -0.2286 -0.0381) (xy -0.22733 -0.04953) (xy -0.22733 -0.05969)
						(xy -0.22606 -0.07112) (xy -0.22352 -0.08128) (xy -0.22225 -0.09144) (xy -0.21844 -0.10287) (xy -0.2159 -0.11303)
						(xy -0.21209 -0.12319) (xy -0.20701 -0.13335) (xy -0.2032 -0.14224) (xy -0.19812 -0.1524) (xy -0.17272 -0.18796)
						(xy -0.1651 -0.19558) (xy -0.1651 -0.7366) (xy -0.16256 -0.76835) (xy -0.1524 -0.8001) (xy -0.13716 -0.82804)
						(xy -0.11684 -0.85344) (xy -0.09144 -0.87376) (xy -0.0635 -0.889) (xy -0.03175 -0.89916) (xy 0 -0.9017)
						(xy 0.03175 -0.89916) (xy 0.0635 -0.889) (xy 0.09144 -0.87376) (xy 0.11684 -0.85344) (xy 0.13716 -0.82804)
						(xy 0.1524 -0.8001) (xy 0.16256 -0.76835) (xy 0.1651 -0.7366) (xy 0.1651 -0.19685) (xy 0.17272 -0.18923)
						(xy 0.17907 -0.18034) (xy 0.18669 -0.17145) (xy 0.19177 -0.16256) (xy 0.19812 -0.15367) (xy 0.20828 -0.13335)
						(xy 0.21971 -0.10287) (xy 0.22225 -0.09271) (xy 0.22479 -0.08128) (xy 0.22606 -0.07112) (xy 0.2286 -0.05969)
						(xy 0.2286 -0.01651) (xy 0.22606 -0.00508) (xy 0.22479 0.00508) (xy 0.22225 0.01651) (xy 0.21971 0.02667)
						(xy 0.20828 0.05715) (xy 0.19812 0.07747) (xy 0.19177 0.08636) (xy 0.18669 0.09525) (xy 0.17907 0.10414)
						(xy 0.17272 0.11303) (xy 0.1651 0.12065) (xy 0.1651 0.7366) (xy 0.16256 0.76835) (xy 0.1524 0.8001)
						(xy 0.13716 0.82804) (xy 0.11684 0.85344) (xy 0.09144 0.87376) (xy 0.0635 0.889) (xy 0.03175 0.89916)
					)
					(width 0)
					(fill yes)
				)
			)
		)
	)
)
